FILE_TYPE = CONNECTIVITY;
{Allegro Design Entry HDL 17.2-2016 S081 (4005846) 1/11/2022}
"PAGE_NUMBER" = 98;
0"NC";
1"P3V3_AUX\g";
2"P12V_S3_AUX_CPU1_NVDIMM\g";
3"P12V_S3_AUX_CPU1_NVDIMM\g";
4"P3V3_AUX\g";
5"GND\g";
6"GND\g";
7"GND\g";
8"GND\g";
9"GND\g";
10"M_A_CPU1_SA_DQ<31:0>";
11"M_A_CPU1_SA_CB<7:0>";
12"M_A_CPU1_SB_CB<7:0>";
13"M_A_CPU1_SA_CA<6:0>";
14"M_A_CPU1_SB_CA<6:0>";
15"M_A_CPU1_SB_DQ<31:0>";
16"M_A_CPU1_SB_DQS_DP<9:0>";
17"M_A_CPU1_SA_DQS_DP<9:0>";
18"M_A_CPU1_SB_DQS_DN<9:0>";
19"M_A_CPU1_SA_DQS_DN<9:0>";
20"PD_CHA_CPU1_DIMM1_SAA";
21"I3C_SPD_DDRABCD_CPU1_LVC1_SDA";
22"I3C_SPD_DDRABCD_CPU1_LVC1_SCL_R1";
23"M_A_CPU1_ALERT_N";
24"RST_M_AB_CPU1_FPGA_N";
25"I3C_SPD_DDRABCD_CPU1_LVC1_SCL";
26"PWRGD_CHA_CPU1_DIMM1";
27"M_A_CPU1_SB_CB<0>";
28"M_A_CPU1_SB_CB<1>";
29"M_A_CPU1_SB_CS_N<1>";
30"M_A_CPU1_SA_CS_N<0>";
31"M_A_CPU1_SB_DQS_DN<6>";
32"M_A_CPU1_SA_DQS_DN<9>";
33"M_A_CPU1_SA_DQS_DN<8>";
34"M_A_CPU1_SA_DQS_DN<6>";
35"M_A_CPU1_SA_DQS_DN<7>";
36"M_A_CPU1_SA_DQS_DN<5>";
37"M_A_CPU1_SA_DQS_DN<4>";
38"M_A_CPU1_SA_DQS_DN<3>";
39"M_A_CPU1_SA_DQS_DN<1>";
40"M_A_CPU1_SA_DQS_DN<2>";
41"M_A_CPU1_SA_DQS_DN<0>";
42"M_A_CPU1_SB_DQS_DN<9>";
43"M_A_CPU1_SB_DQS_DN<8>";
44"M_A_CPU1_SB_DQS_DN<7>";
45"M_A_CPU1_SB_DQS_DN<5>";
46"M_A_CPU1_SB_DQS_DN<4>";
47"M_A_CPU1_SB_DQS_DN<3>";
48"M_A_CPU1_SB_DQS_DN<2>";
49"M_A_CPU1_SB_DQS_DN<0>";
50"M_A_CPU1_SB_DQS_DN<1>";
51"M_A_CPU1_SA_DQS_DP<9>";
52"M_A_CPU1_SA_DQS_DP<8>";
53"M_A_CPU1_SA_DQS_DP<7>";
54"M_A_CPU1_SA_DQS_DP<6>";
55"M_A_CPU1_SA_DQS_DP<5>";
56"M_A_CPU1_SA_DQS_DP<4>";
57"M_A_CPU1_SA_DQS_DP<3>";
58"M_A_CPU1_SA_DQS_DP<2>";
59"M_A_CPU1_SA_DQS_DP<1>";
60"M_A_CPU1_SA_DQS_DP<0>";
61"M_A_CPU1_SB_DQS_DP<9>";
62"M_A_CPU1_SB_DQS_DP<8>";
63"M_A_CPU1_SB_DQS_DP<7>";
64"M_A_CPU1_SB_DQS_DP<6>";
65"M_A_CPU1_SB_DQS_DP<5>";
66"M_A_CPU1_SB_DQS_DP<4>";
67"M_A_CPU1_SB_DQS_DP<3>";
68"M_A_CPU1_SB_DQS_DP<2>";
69"M_A_CPU1_SB_DQS_DP<1>";
70"M_A_CPU1_SB_DQS_DP<0>";
71"M_A_CPU1_SA_CB<2>";
72"TP_CHA_CPU1_DIMM1_FRU_6";
73"TP_CHA_CPU1_DIMM1_FRU_5";
74"TP_CHA_CPU1_DIMM1_FRU_4";
75"M_A_CPU1_SB_CB<2>";
76"M_A_CPU1_SB_CB<3>";
77"M_A_CPU1_SB_DQ<9>";
78"M_A_CPU1_SB_DQ<8>";
79"M_A_CPU1_SA_PAR";
80"M_A_CPU1_SB_PAR";
81"M_A_CPU1_SB_CA<6>";
82"M_A_CPU1_CLK_DN<0>";
83"M_A_CPU1_CLK_DP<0>";
84"TP_CHA_CPU1_DIMM1_FRU_0";
85"TP_CHA_CPU1_DIMM1_FRU_1";
86"TP_CHA_CPU1_DIMM1_FRU_2";
87"TP_CHA_CPU1_DIMM1_FRU_3";
88"M_A_CPU1_SB_RSP<0>";
89"M_A_CPU1_SA_RSP<0>";
90"M_A_CPU1_SB_DQ<0>";
91"M_A_CPU1_SB_DQ<1>";
92"M_A_CPU1_SB_DQ<2>";
93"M_A_CPU1_SB_DQ<3>";
94"M_A_CPU1_SB_DQ<4>";
95"M_A_CPU1_SB_DQ<5>";
96"M_A_CPU1_SB_DQ<6>";
97"M_A_CPU1_SB_DQ<7>";
98"M_A_CPU1_SB_DQ<10>";
99"M_A_CPU1_SB_DQ<11>";
100"M_A_CPU1_SB_DQ<12>";
101"M_A_CPU1_SB_DQ<13>";
102"M_A_CPU1_SB_DQ<14>";
103"M_A_CPU1_SB_DQ<15>";
104"M_A_CPU1_SB_DQ<16>";
105"M_A_CPU1_SB_DQ<17>";
106"M_A_CPU1_SB_DQ<18>";
107"M_A_CPU1_SB_DQ<19>";
108"M_A_CPU1_SB_DQ<20>";
109"M_A_CPU1_SB_DQ<21>";
110"M_A_CPU1_SB_DQ<22>";
111"M_A_CPU1_SB_DQ<23>";
112"M_A_CPU1_SB_DQ<24>";
113"M_A_CPU1_SB_DQ<25>";
114"M_A_CPU1_SB_DQ<26>";
115"M_A_CPU1_SB_DQ<27>";
116"M_A_CPU1_SB_DQ<28>";
117"M_A_CPU1_SB_DQ<29>";
118"M_A_CPU1_SB_DQ<30>";
119"M_A_CPU1_SB_DQ<31>";
120"M_A_CPU1_SA_DQ<0>";
121"M_A_CPU1_SA_DQ<1>";
122"M_A_CPU1_SA_DQ<2>";
123"M_A_CPU1_SA_DQ<3>";
124"M_A_CPU1_SA_DQ<4>";
125"M_A_CPU1_SA_DQ<5>";
126"M_A_CPU1_SA_DQ<6>";
127"M_A_CPU1_SA_DQ<7>";
128"M_A_CPU1_SA_DQ<8>";
129"M_A_CPU1_SA_DQ<9>";
130"M_A_CPU1_SA_DQ<10>";
131"M_A_CPU1_SA_DQ<11>";
132"M_A_CPU1_SA_DQ<12>";
133"M_A_CPU1_SA_DQ<13>";
134"M_A_CPU1_SA_DQ<14>";
135"M_A_CPU1_SA_DQ<15>";
136"M_A_CPU1_SA_DQ<16>";
137"M_A_CPU1_SA_DQ<17>";
138"M_A_CPU1_SA_DQ<18>";
139"M_A_CPU1_SA_DQ<19>";
140"M_A_CPU1_SA_DQ<20>";
141"M_A_CPU1_SA_DQ<21>";
142"M_A_CPU1_SA_DQ<22>";
143"M_A_CPU1_SA_DQ<23>";
144"M_A_CPU1_SA_DQ<24>";
145"M_A_CPU1_SA_DQ<25>";
146"M_A_CPU1_SA_DQ<26>";
147"M_A_CPU1_SA_DQ<27>";
148"M_A_CPU1_SA_DQ<28>";
149"M_A_CPU1_SA_DQ<29>";
150"M_A_CPU1_SA_DQ<30>";
151"M_A_CPU1_SA_CS_N<1>";
152"M_A_CPU1_SB_CS_N<0>";
153"M_A_CPU1_SB_CB<4>";
154"M_A_CPU1_SB_CB<5>";
155"M_A_CPU1_SB_CB<6>";
156"M_A_CPU1_SA_CB<0>";
157"M_A_CPU1_SA_CB<3>";
158"M_A_CPU1_SA_CB<5>";
159"M_A_CPU1_SA_CB<6>";
160"M_A_CPU1_SA_CA<6>";
161"M_A_CPU1_SB_CA<5>";
162"M_A_CPU1_SA_CA<5>";
163"M_A_CPU1_SB_CA<4>";
164"M_A_CPU1_SA_CA<4>";
165"M_A_CPU1_SB_CA<3>";
166"M_A_CPU1_SA_CA<3>";
167"M_A_CPU1_SB_CA<2>";
168"M_A_CPU1_SA_CA<2>";
169"M_A_CPU1_SB_CA<1>";
170"M_A_CPU1_SA_CA<1>";
171"M_A_CPU1_SB_CA<0>";
172"M_A_CPU1_SA_CA<0>";
173"M_A_CPU1_SB_CB<7>";
174"M_A_CPU1_SA_CB<1>";
175"M_A_CPU1_SA_CB<4>";
176"M_A_CPU1_SA_CB<7>";
177"M_A_CPU1_SA_DQ<31>";
178"PD_CHA_CPU1_DIMM1_SAA";
%"UNIVERSAL_GND"
"1","(-1400,-300)","0","logical_power","I1";
;
CDS_LIB"logical_power"
HDL_POWER"GND";
"A"9;
%"TAP"
"1","(25,3425)","0","standard","I100";
;
CDS_LIB"standard"
BODY_TYPE"PLUMBING"
HDL_TAP"TRUE";
"B \NAC \NWC"10;
"S \NAC"
BN"18"138;
%"TAP"
"1","(25,3375)","0","standard","I101";
;
CDS_LIB"standard"
BODY_TYPE"PLUMBING"
HDL_TAP"TRUE";
"B \NAC \NWC"10;
"S \NAC"
BN"17"137;
%"TAP"
"1","(25,3525)","0","standard","I102";
;
CDS_LIB"standard"
BODY_TYPE"PLUMBING"
HDL_TAP"TRUE";
"B \NAC \NWC"10;
"S \NAC"
BN"20"140;
%"TAP"
"1","(25,3575)","0","standard","I103";
;
CDS_LIB"standard"
BODY_TYPE"PLUMBING"
HDL_TAP"TRUE";
"B \NAC \NWC"10;
"S \NAC"
BN"21"141;
%"TAP"
"1","(25,3625)","0","standard","I104";
;
CDS_LIB"standard"
BODY_TYPE"PLUMBING"
HDL_TAP"TRUE";
"B \NAC \NWC"10;
"S \NAC"
BN"22"142;
%"TAP"
"1","(25,3675)","0","standard","I105";
;
CDS_LIB"standard"
BODY_TYPE"PLUMBING"
HDL_TAP"TRUE";
"B \NAC \NWC"10;
"S \NAC"
BN"23"143;
%"TAP"
"1","(25,3725)","0","standard","I106";
;
CDS_LIB"standard"
BODY_TYPE"PLUMBING"
HDL_TAP"TRUE";
"B \NAC \NWC"10;
"S \NAC"
BN"24"144;
%"TAP"
"1","(25,3775)","0","standard","I107";
;
CDS_LIB"standard"
BODY_TYPE"PLUMBING"
HDL_TAP"TRUE";
"B \NAC \NWC"10;
"S \NAC"
BN"25"145;
%"TAP"
"1","(25,3825)","0","standard","I108";
;
CDS_LIB"standard"
BODY_TYPE"PLUMBING"
HDL_TAP"TRUE";
"B \NAC \NWC"10;
"S \NAC"
BN"26"146;
%"Q_RES"
"2","(-1400,-75)","0","pure_quanta","I11";
;
PART_NUMBER"CS31002FB08"
WATTAGE"1/16W"
TOLERANCE"1%"
MATERIAL"CHIP"
PACK_TYPE"0402LF"
VALUE"10K"
$LOCATION"R42"
CDS_LIB"pure_quanta"
CDS_LOCATION"R42"
$SEC"1"
CDS_SEC"1";
"A"
$PN"1"178;
"B"
$PN"2"9;
%"TAP"
"1","(-1625,3875)","2","standard","I110";
;
CDS_LIB"standard"
BODY_TYPE"PLUMBING"
HDL_TAP"TRUE";
"B \NAC \NWC"13;
"S \NAC"
BN"2"168;
%"TAP"
"1","(-1625,3925)","2","standard","I111";
;
CDS_LIB"standard"
BODY_TYPE"PLUMBING"
HDL_TAP"TRUE";
"B \NAC \NWC"13;
"S \NAC"
BN"3"166;
%"TAP"
"1","(-1625,3975)","2","standard","I112";
;
CDS_LIB"standard"
BODY_TYPE"PLUMBING"
HDL_TAP"TRUE";
"B \NAC \NWC"13;
"S \NAC"
BN"4"164;
%"TAP"
"1","(-1625,4075)","2","standard","I113";
;
CDS_LIB"standard"
BODY_TYPE"PLUMBING"
HDL_TAP"TRUE";
"B \NAC \NWC"13;
"S \NAC"
BN"6"160;
%"TAP"
"1","(-1625,4025)","2","standard","I114";
;
CDS_LIB"standard"
BODY_TYPE"PLUMBING"
HDL_TAP"TRUE";
"B \NAC \NWC"13;
"S \NAC"
BN"5"162;
%"TAP"
"1","(25,3975)","0","standard","I115";
;
CDS_LIB"standard"
BODY_TYPE"PLUMBING"
HDL_TAP"TRUE";
"B \NAC \NWC"10;
"S \NAC"
BN"29"149;
%"TAP"
"1","(25,3875)","0","standard","I116";
;
CDS_LIB"standard"
BODY_TYPE"PLUMBING"
HDL_TAP"TRUE";
"B \NAC \NWC"10;
"S \NAC"
BN"27"147;
%"TAP"
"1","(25,3925)","0","standard","I117";
;
CDS_LIB"standard"
BODY_TYPE"PLUMBING"
HDL_TAP"TRUE";
"B \NAC \NWC"10;
"S \NAC"
BN"28"148;
%"TAP"
"1","(25,4025)","0","standard","I118";
;
CDS_LIB"standard"
BODY_TYPE"PLUMBING"
HDL_TAP"TRUE";
"B \NAC \NWC"10;
"S \NAC"
BN"30"150;
%"TAP"
"1","(25,4075)","0","standard","I119";
;
CDS_LIB"standard"
BODY_TYPE"PLUMBING"
HDL_TAP"TRUE";
"B \NAC \NWC"10;
"S \NAC"
BN"31"177;
%"SCONN288_ADR50017P130CC"
"1","(-800,2350)","0","pure_quanta","I12";
;
PART_NUMBER"DFHST8FS461"
MATERIAL"IO"
VALUE"SCONN288_ADR50017-P130CC"
PART_TYPE"SMLF"
$LOCATION"J17"
NEEDS_NO_SIZE"TRUE"
CDS_LMAN_SYM_OUTLINE"-450,1875,450,-1875"
CDS_LIB"pure_quanta"
CDS_LOCATION"J17"
$SEC"1"
CDS_SEC"1";
"DQ31_A"
$PN"194"177;
"CB7_A"
$PN"205"176;
"CB4_A"
$PN"58"175;
"CB1_A"
$PN"53"174;
"CB7_B"
$PN"236"173;
"ALERT_N \B"
$PN"62"23;
"CA0_A"
$PN"66"172;
"CA0_B"
$PN"76"171;
"CA1_A"
$PN"211"170;
"CA1_B"
$PN"221"169;
"CA2_A"
$PN"68"168;
"CA2_B"
$PN"78"167;
"CA3_A"
$PN"213"166;
"CA3_B"
$PN"223"165;
"CA4_A"
$PN"70"164;
"CA4_B"
$PN"80"163;
"CA5_A"
$PN"215"162;
"CA5_B"
$PN"225"161;
"CA6_A"
$PN"72"160;
"CA6_B"
$PN"82"81;
"CB6_A"
$PN"203"159;
"CB5_A"
$PN"60"158;
"CB3_A"
$PN"198"157;
"CB2_A"
$PN"196"71;
"CB0_A"
$PN"51"156;
"CB6_B"
$PN"234"155;
"CB5_B"
$PN"91"154;
"CB4_B"
$PN"89"153;
"CB3_B"
$PN"243"76;
"CB2_B"
$PN"241"75;
"CB1_B"
$PN"98"28;
"CB0_B"
$PN"96"27;
"CK_C \B"
$PN"218"82;
"CK_T"
$PN"217"83;
"CS0_A_N"
$PN"64"30;
"CS0_B_N"
$PN"84"152;
"CS1_A_N"
$PN"209"151;
"CS1_B_N"
$PN"229"29;
"DQ30_A"
$PN"192"150;
"DQ29_A"
$PN"49"149;
"DQ28_A"
$PN"47"148;
"DQ27_A"
$PN"187"147;
"DQ26_A"
$PN"185"146;
"DQ25_A"
$PN"42"145;
"DQ24_A"
$PN"40"144;
"DQ23_A"
$PN"183"143;
"DQ22_A"
$PN"181"142;
"DQ21_A"
$PN"38"141;
"DQ20_A"
$PN"36"140;
"DQ19_A"
$PN"176"139;
"DQ18_A"
$PN"174"138;
"DQ17_A"
$PN"31"137;
"DQ16_A"
$PN"29"136;
"DQ15_A"
$PN"172"135;
"DQ14_A"
$PN"170"134;
"DQ13_A"
$PN"27"133;
"DQ12_A"
$PN"25"132;
"DQ11_A"
$PN"165"131;
"DQ10_A"
$PN"163"130;
"DQ9_A"
$PN"20"129;
"DQ8_A"
$PN"18"128;
"DQ7_A"
$PN"161"127;
"DQ6_A"
$PN"159"126;
"DQ5_A"
$PN"16"125;
"DQ4_A"
$PN"14"124;
"DQ3_A"
$PN"154"123;
"DQ2_A"
$PN"152"122;
"DQ1_A"
$PN"9"121;
"DQ0_A"
$PN"7"120;
"DQ31_B"
$PN"287"119;
"DQ30_B"
$PN"285"118;
"DQ29_B"
$PN"142"117;
"DQ28_B"
$PN"140"116;
"DQ27_B"
$PN"280"115;
"DQ26_B"
$PN"278"114;
"DQ25_B"
$PN"135"113;
"DQ24_B"
$PN"133"112;
"DQ23_B"
$PN"276"111;
"DQ22_B"
$PN"274"110;
"DQ21_B"
$PN"131"109;
"DQ20_B"
$PN"129"108;
"DQ19_B"
$PN"269"107;
"DQ18_B"
$PN"267"106;
"DQ17_B"
$PN"124"105;
"DQ16_B"
$PN"122"104;
"DQ15_B"
$PN"265"103;
"DQ14_B"
$PN"263"102;
"DQ13_B"
$PN"120"101;
"DQ12_B"
$PN"118"100;
"DQ11_B"
$PN"258"99;
"DQ10_B"
$PN"256"98;
"DQ9_B"
$PN"113"77;
"DQ8_B"
$PN"111"78;
"DQ7_B"
$PN"254"97;
"DQ6_B"
$PN"252"96;
"DQ5_B"
$PN"109"95;
"DQ4_B"
$PN"107"94;
"DQ3_B"
$PN"247"93;
"DQ2_B"
$PN"245"92;
"DQ1_B"
$PN"102"91;
"DQ0_B"
$PN"100"90;
"HSA"
$PN"148"20;
"HSCL"
$PN"4"22;
"HSDA"
$PN"5"21;
"LBD||RSP_A_N"
$PN"86"89;
"LBS||RSP_B_N"
$PN"87"88;
"PAR_A"
$PN"74"79;
"PAR_B"
$PN"227"80;
"PWR_GOOD||FAIL_N"
$PN"147"26;
"RESET_N \B"
$PN"207"24;
"RFU6"
$PN"232"72;
"RFU5"
$PN"231"73;
"RFU4"
$PN"220"74;
"RFU3"
$PN"150"87;
"RFU2"
$PN"149"86;
"RFU1"
$PN"144"85;
"RFU0"
$PN"2"84;
"VIN_MGMT"
$PN"3"1;
%"VCC_CORE"
"1","(1750,525)","0","logical_power","I120";
;
HDL_POWER"P3V3_AUX"
CDS_LIB"logical_power";
"A"4;
%"UNIVERSAL_GND"
"1","(1750,-175)","0","logical_power","I121";
;
CDS_LIB"logical_power"
HDL_POWER"GND";
"A"8;
%"Q_CAP"
"1","(1750,200)","0","pure_quanta","I122";
;
PART_NUMBER"CH5221MEB00"
VALUE"2.2UF"
MATERIAL"X6S"
VOLTAGE"6.3V"
TOLERANCE"20%"
PACK_TYPE"C0402"
$LOCATION"C50"
CDS_LIB"pure_quanta"
CDS_LOCATION"C50"
$SEC"1"
CDS_SEC"1";
"B"
$PN"2"8;
"A"
$PN"1"4;
%"Q_CAP"
"1","(2750,200)","0","pure_quanta","I123";
;
PART_NUMBER"CH6103KEA00"
PACK_TYPE"C0805"
TOLERANCE"10%"
VALUE"10UF"
VOLTAGE"16V"
MATERIAL"X6S"
$LOCATION"C51"
CDS_LIB"pure_quanta"
CDS_LOCATION"C51"
$SEC"1"
CDS_SEC"1";
"B"
$PN"2"7;
"A"
$PN"1"3;
%"VCC_CORE"
"1","(2750,525)","0","logical_power","I124";
;
HDL_POWER"P12V_S3_AUX_CPU1_NVDIMM"
CDS_LIB"logical_power";
"A"3;
%"TAP"
"1","(2775,2125)","0","standard","I127";
;
CDS_LIB"standard"
BODY_TYPE"PLUMBING"
HDL_TAP"TRUE";
"B \NAC \NWC"16;
"S \NAC"
BN"0"70;
%"TAP"
"1","(2775,2325)","0","standard","I128";
;
CDS_LIB"standard"
BODY_TYPE"PLUMBING"
HDL_TAP"TRUE";
"B \NAC \NWC"16;
"S \NAC"
BN"2"68;
%"TAP"
"1","(2775,2225)","0","standard","I129";
;
CDS_LIB"standard"
BODY_TYPE"PLUMBING"
HDL_TAP"TRUE";
"B \NAC \NWC"16;
"S \NAC"
BN"1"69;
%"TAP"
"1","(2775,2425)","0","standard","I130";
;
CDS_LIB"standard"
BODY_TYPE"PLUMBING"
HDL_TAP"TRUE";
"B \NAC \NWC"16;
"S \NAC"
BN"3"67;
%"TAP"
"1","(2775,2525)","0","standard","I131";
;
CDS_LIB"standard"
BODY_TYPE"PLUMBING"
HDL_TAP"TRUE";
"B \NAC \NWC"16;
"S \NAC"
BN"4"66;
%"TAP"
"1","(2775,2625)","0","standard","I132";
;
CDS_LIB"standard"
BODY_TYPE"PLUMBING"
HDL_TAP"TRUE";
"B \NAC \NWC"16;
"S \NAC"
BN"5"65;
%"TAP"
"1","(2775,2825)","0","standard","I133";
;
CDS_LIB"standard"
BODY_TYPE"PLUMBING"
HDL_TAP"TRUE";
"B \NAC \NWC"16;
"S \NAC"
BN"7"63;
%"TAP"
"1","(2775,2725)","0","standard","I134";
;
CDS_LIB"standard"
BODY_TYPE"PLUMBING"
HDL_TAP"TRUE";
"B \NAC \NWC"16;
"S \NAC"
BN"6"64;
%"TAP"
"1","(2775,2925)","0","standard","I135";
;
CDS_LIB"standard"
BODY_TYPE"PLUMBING"
HDL_TAP"TRUE";
"B \NAC \NWC"16;
"S \NAC"
BN"8"62;
%"TAP"
"1","(2775,3025)","0","standard","I136";
;
CDS_LIB"standard"
BODY_TYPE"PLUMBING"
HDL_TAP"TRUE";
"B \NAC \NWC"16;
"S \NAC"
BN"9"61;
%"TAP"
"1","(2775,3175)","0","standard","I137";
;
CDS_LIB"standard"
BODY_TYPE"PLUMBING"
HDL_TAP"TRUE";
"B \NAC \NWC"17;
"S \NAC"
BN"0"60;
%"TAP"
"1","(2775,3275)","0","standard","I138";
;
CDS_LIB"standard"
BODY_TYPE"PLUMBING"
HDL_TAP"TRUE";
"B \NAC \NWC"17;
"S \NAC"
BN"1"59;
%"TAP"
"1","(2775,3375)","0","standard","I139";
;
CDS_LIB"standard"
BODY_TYPE"PLUMBING"
HDL_TAP"TRUE";
"B \NAC \NWC"17;
"S \NAC"
BN"2"58;
%"VCC_CORE"
"1","(-2450,1950)","0","logical_power","I14";
;
HDL_POWER"P3V3_AUX"
CDS_LIB"logical_power";
"A"1;
%"TAP"
"1","(2775,3475)","0","standard","I140";
;
CDS_LIB"standard"
BODY_TYPE"PLUMBING"
HDL_TAP"TRUE";
"B \NAC \NWC"17;
"S \NAC"
BN"3"57;
%"TAP"
"1","(2775,3575)","0","standard","I141";
;
CDS_LIB"standard"
BODY_TYPE"PLUMBING"
HDL_TAP"TRUE";
"B \NAC \NWC"17;
"S \NAC"
BN"4"56;
%"TAP"
"1","(2775,3675)","0","standard","I142";
;
CDS_LIB"standard"
BODY_TYPE"PLUMBING"
HDL_TAP"TRUE";
"B \NAC \NWC"17;
"S \NAC"
BN"5"55;
%"TAP"
"1","(2775,3775)","0","standard","I143";
;
CDS_LIB"standard"
BODY_TYPE"PLUMBING"
HDL_TAP"TRUE";
"B \NAC \NWC"17;
"S \NAC"
BN"6"54;
%"UNIVERSAL_GND"
"1","(3375,-175)","0","logical_power","I144";
;
CDS_LIB"logical_power"
HDL_POWER"GND";
"A"7;
%"Q_CAP"
"1","(3375,200)","0","pure_quanta","I145";
;
PART_NUMBER"CH6103KEA00"
TOLERANCE"10%"
VOLTAGE"16V"
VALUE"10UF"
PACK_TYPE"C0805"
MATERIAL"X6S"
$LOCATION"C52"
CDS_LIB"pure_quanta"
CDS_LOCATION"C52"
$SEC"1"
CDS_SEC"1";
"B"
$PN"2"7;
"A"
$PN"1"3;
%"UNIVERSAL_GND"
"1","(4450,375)","0","logical_power","I146";
;
CDS_LIB"logical_power"
HDL_POWER"GND";
"A"6;
%"SCONN288_ADR50017P130CC"
"3","(5300,2450)","0","pure_quanta","I147";
;
PART_NUMBER"DFHST8FS461"
MATERIAL"IO"
VALUE"SCONN288_ADR50017-P130CC"
PART_TYPE"SMLF"
$LOCATION"J17"
NEEDS_NO_SIZE"TRUE"
CDS_LMAN_SYM_OUTLINE"-450,1775,450,-1775"
CDS_LIB"pure_quanta"
CDS_LOCATION"J17"
$SEC"3"
CDS_SEC"3";
"G3"
$PN"G3"5;
"G2"
$PN"G2"5;
"G1"
$PN"G1"5;
"VSS62"
$PN"141"5;
"VSS61"
$PN"139"5;
"VSS60"
$PN"136"5;
"VSS58"
$PN"132"5;
"VSS104"
$PN"240"6;
"VSS102"
$PN"235"6;
"VSS100"
$PN"230"6;
"VIN_BULK2"
$PN"146"2;
"VIN_BULK1"
$PN"145"2;
"VIN_BULK0"
$PN"1"2;
"VSS126"
$PN"288"6;
"VSS125"
$PN"286"6;
"VSS124"
$PN"284"6;
"VSS123"
$PN"281"6;
"VSS122"
$PN"279"6;
"VSS121"
$PN"277"6;
"VSS120"
$PN"275"6;
"VSS119"
$PN"273"6;
"VSS118"
$PN"270"6;
"VSS117"
$PN"268"6;
"VSS116"
$PN"266"6;
"VSS115"
$PN"264"6;
"VSS114"
$PN"262"6;
"VSS113"
$PN"259"6;
"VSS112"
$PN"257"6;
"VSS111"
$PN"255"6;
"VSS110"
$PN"253"6;
"VSS109"
$PN"251"6;
"VSS108"
$PN"248"6;
"VSS107"
$PN"246"6;
"VSS106"
$PN"244"6;
"VSS105"
$PN"242"6;
"VSS103"
$PN"237"6;
"VSS101"
$PN"233"6;
"VSS99"
$PN"228"6;
"VSS98"
$PN"226"6;
"VSS97"
$PN"224"6;
"VSS96"
$PN"222"6;
"VSS95"
$PN"219"6;
"VSS94"
$PN"216"6;
"VSS93"
$PN"214"6;
"VSS92"
$PN"212"6;
"VSS91"
$PN"210"6;
"VSS90"
$PN"208"6;
"VSS89"
$PN"206"6;
"VSS88"
$PN"204"6;
"VSS87"
$PN"202"6;
"VSS86"
$PN"199"6;
"VSS85"
$PN"197"6;
"VSS84"
$PN"195"6;
"VSS83"
$PN"193"6;
"VSS82"
$PN"191"6;
"VSS81"
$PN"188"6;
"VSS80"
$PN"186"6;
"VSS79"
$PN"184"6;
"VSS78"
$PN"182"6;
"VSS77"
$PN"180"6;
"VSS76"
$PN"177"6;
"VSS75"
$PN"175"6;
"VSS74"
$PN"173"6;
"VSS73"
$PN"171"6;
"VSS72"
$PN"169"6;
"VSS71"
$PN"166"6;
"VSS70"
$PN"164"6;
"VSS69"
$PN"162"6;
"VSS68"
$PN"160"6;
"VSS67"
$PN"158"6;
"VSS66"
$PN"155"6;
"VSS65"
$PN"153"6;
"VSS64"
$PN"151"6;
"VSS63"
$PN"143"5;
"VSS59"
$PN"134"5;
"VSS57"
$PN"130"5;
"VSS56"
$PN"128"5;
"VSS55"
$PN"125"5;
"VSS54"
$PN"123"5;
"VSS53"
$PN"121"5;
"VSS52"
$PN"119"5;
"VSS51"
$PN"117"5;
"VSS50"
$PN"114"5;
"VSS49"
$PN"112"5;
"VSS48"
$PN"110"5;
"VSS47"
$PN"108"5;
"VSS46"
$PN"106"5;
"VSS45"
$PN"103"5;
"VSS44"
$PN"101"5;
"VSS43"
$PN"99"5;
"VSS42"
$PN"97"5;
"VSS41"
$PN"95"5;
"VSS40"
$PN"92"5;
"VSS39"
$PN"90"5;
"VSS38"
$PN"88"5;
"VSS37"
$PN"85"5;
"VSS36"
$PN"83"5;
"VSS35"
$PN"81"5;
"VSS34"
$PN"79"5;
"VSS33"
$PN"77"5;
"VSS32"
$PN"75"5;
"VSS31"
$PN"73"5;
"VSS30"
$PN"71"5;
"VSS29"
$PN"69"5;
"VSS28"
$PN"67"5;
"VSS27"
$PN"65"5;
"VSS26"
$PN"63"5;
"VSS25"
$PN"61"5;
"VSS24"
$PN"59"5;
"VSS23"
$PN"57"5;
"VSS22"
$PN"54"5;
"VSS21"
$PN"52"5;
"VSS20"
$PN"50"5;
"VSS19"
$PN"48"5;
"VSS18"
$PN"46"5;
"VSS17"
$PN"43"5;
"VSS16"
$PN"41"5;
"VSS15"
$PN"39"5;
"VSS14"
$PN"37"5;
"VSS13"
$PN"35"5;
"VSS12"
$PN"32"5;
"VSS11"
$PN"30"5;
"VSS10"
$PN"28"5;
"VSS9"
$PN"26"5;
"VSS8"
$PN"24"5;
"VSS7"
$PN"21"5;
"VSS6"
$PN"19"5;
"VSS5"
$PN"17"5;
"VSS4"
$PN"15"5;
"VSS3"
$PN"13"5;
"VSS2"
$PN"10"5;
"VSS1"
$PN"8"5;
"VSS0"
$PN"6"5;
%"TAP"
"1","(2950,2075)","0","standard","I148";
;
CDS_LIB"standard"
BODY_TYPE"PLUMBING"
HDL_TAP"TRUE";
"B \NAC \NWC"18;
"S \NAC"
BN"0"49;
%"TAP"
"1","(2950,2175)","0","standard","I149";
;
CDS_LIB"standard"
BODY_TYPE"PLUMBING"
HDL_TAP"TRUE";
"B \NAC \NWC"18;
"S \NAC"
BN"1"50;
%"TAP"
"1","(2950,2275)","0","standard","I150";
;
CDS_LIB"standard"
BODY_TYPE"PLUMBING"
HDL_TAP"TRUE";
"B \NAC \NWC"18;
"S \NAC"
BN"2"48;
%"TAP"
"1","(2950,2375)","0","standard","I151";
;
CDS_LIB"standard"
BODY_TYPE"PLUMBING"
HDL_TAP"TRUE";
"B \NAC \NWC"18;
"S \NAC"
BN"3"47;
%"TAP"
"1","(2950,2575)","0","standard","I152";
;
CDS_LIB"standard"
BODY_TYPE"PLUMBING"
HDL_TAP"TRUE";
"B \NAC \NWC"18;
"S \NAC"
BN"5"45;
%"TAP"
"1","(2950,2475)","0","standard","I153";
;
CDS_LIB"standard"
BODY_TYPE"PLUMBING"
HDL_TAP"TRUE";
"B \NAC \NWC"18;
"S \NAC"
BN"4"46;
%"TAP"
"1","(2950,2675)","0","standard","I154";
;
CDS_LIB"standard"
BODY_TYPE"PLUMBING"
HDL_TAP"TRUE";
"B \NAC \NWC"18;
"S \NAC"
BN"6"31;
%"TAP"
"1","(2950,2775)","0","standard","I155";
;
CDS_LIB"standard"
BODY_TYPE"PLUMBING"
HDL_TAP"TRUE";
"B \NAC \NWC"18;
"S \NAC"
BN"7"44;
%"TAP"
"1","(2950,2875)","0","standard","I156";
;
CDS_LIB"standard"
BODY_TYPE"PLUMBING"
HDL_TAP"TRUE";
"B \NAC \NWC"18;
"S \NAC"
BN"8"43;
%"TAP"
"1","(2950,2975)","0","standard","I157";
;
CDS_LIB"standard"
BODY_TYPE"PLUMBING"
HDL_TAP"TRUE";
"B \NAC \NWC"18;
"S \NAC"
BN"9"42;
%"TAP"
"1","(2950,3225)","0","standard","I158";
;
CDS_LIB"standard"
BODY_TYPE"PLUMBING"
HDL_TAP"TRUE";
"B \NAC \NWC"19;
"S \NAC"
BN"1"39;
%"TAP"
"1","(2950,3125)","0","standard","I159";
;
CDS_LIB"standard"
BODY_TYPE"PLUMBING"
HDL_TAP"TRUE";
"B \NAC \NWC"19;
"S \NAC"
BN"0"41;
%"TAP"
"1","(2950,3325)","0","standard","I160";
;
CDS_LIB"standard"
BODY_TYPE"PLUMBING"
HDL_TAP"TRUE";
"B \NAC \NWC"19;
"S \NAC"
BN"2"40;
%"TAP"
"1","(2950,3425)","0","standard","I161";
;
CDS_LIB"standard"
BODY_TYPE"PLUMBING"
HDL_TAP"TRUE";
"B \NAC \NWC"19;
"S \NAC"
BN"3"38;
%"TAP"
"1","(2950,3525)","0","standard","I162";
;
CDS_LIB"standard"
BODY_TYPE"PLUMBING"
HDL_TAP"TRUE";
"B \NAC \NWC"19;
"S \NAC"
BN"4"37;
%"TAP"
"1","(2950,3725)","0","standard","I163";
;
CDS_LIB"standard"
BODY_TYPE"PLUMBING"
HDL_TAP"TRUE";
"B \NAC \NWC"19;
"S \NAC"
BN"6"34;
%"TAP"
"1","(2950,3625)","0","standard","I164";
;
CDS_LIB"standard"
BODY_TYPE"PLUMBING"
HDL_TAP"TRUE";
"B \NAC \NWC"19;
"S \NAC"
BN"5"36;
%"TAP"
"1","(2950,3825)","0","standard","I165";
;
CDS_LIB"standard"
BODY_TYPE"PLUMBING"
HDL_TAP"TRUE";
"B \NAC \NWC"19;
"S \NAC"
BN"7"35;
%"TAP"
"1","(2775,3875)","0","standard","I169";
;
CDS_LIB"standard"
BODY_TYPE"PLUMBING"
HDL_TAP"TRUE";
"B \NAC \NWC"17;
"S \NAC"
BN"7"53;
%"TAP"
"1","(2775,3975)","0","standard","I170";
;
CDS_LIB"standard"
BODY_TYPE"PLUMBING"
HDL_TAP"TRUE";
"B \NAC \NWC"17;
"S \NAC"
BN"8"52;
%"TAP"
"1","(2775,4075)","0","standard","I171";
;
CDS_LIB"standard"
BODY_TYPE"PLUMBING"
HDL_TAP"TRUE";
"B \NAC \NWC"17;
"S \NAC"
BN"9"51;
%"TAP"
"1","(2950,3925)","0","standard","I172";
;
CDS_LIB"standard"
BODY_TYPE"PLUMBING"
HDL_TAP"TRUE";
"B \NAC \NWC"19;
"S \NAC"
BN"8"33;
%"TAP"
"1","(2950,4025)","0","standard","I173";
;
CDS_LIB"standard"
BODY_TYPE"PLUMBING"
HDL_TAP"TRUE";
"B \NAC \NWC"19;
"S \NAC"
BN"9"32;
%"VCC_CORE"
"1","(4450,4625)","0","logical_power","I176";
;
HDL_POWER"P12V_S3_AUX_CPU1_NVDIMM"
CDS_LIB"logical_power";
"A"2;
%"UNIVERSAL_GND"
"1","(6150,375)","0","logical_power","I177";
;
CDS_LIB"logical_power"
HDL_POWER"GND";
"A"5;
%"SCONN288_ADR50017P130CC"
"2","(1875,3075)","0","pure_quanta","I178";
;
PART_NUMBER"DFHST8FS461"
MATERIAL"IO"
PART_TYPE"SMLF"
VALUE"SCONN288_ADR50017-P130CC"
LOCATION"J17"
CDS_LIB"pure_quanta"
CDS_LMAN_SYM_OUTLINE"-600,1150,600,-1150"
NEEDS_NO_SIZE"TRUE"
$SEC"2"
CDS_SEC"2";
"DQS7_A_C||TDQS7_A_C \B"
$PN"178"35;
"DQS6_A_T||TDQS6_A_T"
$PN"168"54;
"DQS8_B_T||TDQS8_B_T"
$PN"283"62;
"DQS8_B_C||TDQS8_B_C \B"
$PN"282"43;
"DQS7_B_T||TDQS7_B_T"
$PN"272"63;
"DQS0_A_C \B"
$PN"12"41;
"DQS0_A_T"
$PN"11"60;
"DQS0_B_C \B"
$PN"105"49;
"DQS0_B_T"
$PN"104"70;
"DQS1_A_C \B"
$PN"23"39;
"DQS1_A_T"
$PN"22"59;
"DQS1_B_C \B"
$PN"116"50;
"DQS1_B_T"
$PN"115"69;
"DQS2_A_C \B"
$PN"34"40;
"DQS2_A_T"
$PN"33"58;
"DQS2_B_C \B"
$PN"127"48;
"DQS2_B_T"
$PN"126"68;
"DQS3_A_C \B"
$PN"45"38;
"DQS3_A_T"
$PN"44"57;
"DQS3_B_C \B"
$PN"138"47;
"DQS3_B_T"
$PN"137"67;
"DQS4_A_C \B"
$PN"56"37;
"DQS4_A_T"
$PN"55"56;
"DQS4_B_C \B"
$PN"238"46;
"DQS4_B_T"
$PN"239"66;
"DQS5_A_C||TDQS5_A_C||DQS5_A_T||TDQS5_A_T \B"
$PN"156"36;
"DQS5_A_T||TDQS5_A_T"
$PN"157"55;
"DQS5_B_C||TDQS5_B_C \B"
$PN"249"45;
"DQS5_B_T||TDQS5_B_T"
$PN"250"65;
"DQS6_A_C||TDQS6_A_C||DQS6_A_T||TDQS6_A_T \B"
$PN"167"34;
"DQS6_B_C||TDQS6_B_C \B"
$PN"260"31;
"DQS6_B_T||TDQS6_B_T"
$PN"261"64;
"DQS7_A_T||TDQS7_A_T"
$PN"179"53;
"DQS7_B_C||TDQS7_B_C \B"
$PN"271"44;
"DQS8_A_C||TDQS8_A_C \B"
$PN"189"33;
"DQS8_A_T||TDQS8_A_T"
$PN"190"52;
"DQS9_A_C||TDQS9_A_C \B"
$PN"200"32;
"DQS9_A_T||TDQS9_A_T"
$PN"201"51;
"DQS9_B_C||TDQS9_B_C \B"
$PN"94"42;
"DQS9_B_T||TDQS9_B_T||DBI4_B_N"
$PN"93"61;
%"Q_RES"
"1","(-2625,1350)","0","pure_quanta","I179";
;
PART_NUMBER"CS04992FB07"
VALUE"49.9"
MATERIAL"CHIP"
$LOCATION"R3891"
CDS_LIB"pure_quanta"
PACK_TYPE"0402LF"
TOLERANCE"1%"
WATTAGE"1/16W"
CDS_LOCATION"R3891"
$SEC"1"
CDS_SEC"1";
"B"
$PN"2"25;
"A"
$PN"1"22;
%"TAP"
"1","(-1625,1925)","2","standard","I25";
;
CDS_LIB"standard"
BODY_TYPE"PLUMBING"
HDL_TAP"TRUE";
"B \NAC \NWC"12;
"S \NAC"
BN"1"28;
%"TAP"
"1","(-1625,1875)","2","standard","I26";
;
CDS_LIB"standard"
BODY_TYPE"PLUMBING"
HDL_TAP"TRUE";
"B \NAC \NWC"12;
"S \NAC"
BN"0"27;
%"TAP"
"1","(-1625,1975)","2","standard","I27";
;
CDS_LIB"standard"
BODY_TYPE"PLUMBING"
HDL_TAP"TRUE";
"B \NAC \NWC"12;
"S \NAC"
BN"2"75;
%"TAP"
"1","(-1625,2025)","2","standard","I28";
;
CDS_LIB"standard"
BODY_TYPE"PLUMBING"
HDL_TAP"TRUE";
"B \NAC \NWC"12;
"S \NAC"
BN"3"76;
%"TAP"
"1","(-1625,2075)","2","standard","I29";
;
CDS_LIB"standard"
BODY_TYPE"PLUMBING"
HDL_TAP"TRUE";
"B \NAC \NWC"12;
"S \NAC"
BN"4"153;
%"TAP"
"1","(-1625,2175)","2","standard","I30";
;
CDS_LIB"standard"
BODY_TYPE"PLUMBING"
HDL_TAP"TRUE";
"B \NAC \NWC"12;
"S \NAC"
BN"6"155;
%"TAP"
"1","(-1625,2125)","2","standard","I31";
;
CDS_LIB"standard"
BODY_TYPE"PLUMBING"
HDL_TAP"TRUE";
"B \NAC \NWC"12;
"S \NAC"
BN"5"154;
%"TAP"
"1","(-1625,2225)","2","standard","I32";
;
CDS_LIB"standard"
BODY_TYPE"PLUMBING"
HDL_TAP"TRUE";
"B \NAC \NWC"12;
"S \NAC"
BN"7"173;
%"TAP"
"1","(-1625,2325)","2","standard","I33";
;
CDS_LIB"standard"
BODY_TYPE"PLUMBING"
HDL_TAP"TRUE";
"B \NAC \NWC"11;
"S \NAC"
BN"0"156;
%"TAP"
"1","(-1625,2375)","2","standard","I34";
;
CDS_LIB"standard"
BODY_TYPE"PLUMBING"
HDL_TAP"TRUE";
"B \NAC \NWC"11;
"S \NAC"
BN"1"174;
%"TAP"
"1","(-1625,2425)","2","standard","I35";
;
CDS_LIB"standard"
BODY_TYPE"PLUMBING"
HDL_TAP"TRUE";
"B \NAC \NWC"11;
"S \NAC"
BN"2"71;
%"TAP"
"1","(-1625,2475)","2","standard","I36";
;
CDS_LIB"standard"
BODY_TYPE"PLUMBING"
HDL_TAP"TRUE";
"B \NAC \NWC"11;
"S \NAC"
BN"3"157;
%"TAP"
"1","(-1625,2525)","2","standard","I37";
;
CDS_LIB"standard"
BODY_TYPE"PLUMBING"
HDL_TAP"TRUE";
"B \NAC \NWC"11;
"S \NAC"
BN"4"175;
%"TAP"
"1","(-1625,2575)","2","standard","I38";
;
CDS_LIB"standard"
BODY_TYPE"PLUMBING"
HDL_TAP"TRUE";
"B \NAC \NWC"11;
"S \NAC"
BN"5"158;
%"TAP"
"1","(-1625,2675)","2","standard","I39";
;
CDS_LIB"standard"
BODY_TYPE"PLUMBING"
HDL_TAP"TRUE";
"B \NAC \NWC"11;
"S \NAC"
BN"7"176;
%"TAP"
"1","(-1625,2625)","2","standard","I40";
;
CDS_LIB"standard"
BODY_TYPE"PLUMBING"
HDL_TAP"TRUE";
"B \NAC \NWC"11;
"S \NAC"
BN"6"159;
%"TAP"
"1","(-1625,3475)","2","standard","I41";
;
CDS_LIB"standard"
BODY_TYPE"PLUMBING"
HDL_TAP"TRUE";
"B \NAC \NWC"14;
"S \NAC"
BN"2"167;
%"TAP"
"1","(-1625,3425)","2","standard","I42";
;
CDS_LIB"standard"
BODY_TYPE"PLUMBING"
HDL_TAP"TRUE";
"B \NAC \NWC"14;
"S \NAC"
BN"1"169;
%"TAP"
"1","(-1625,3375)","2","standard","I43";
;
CDS_LIB"standard"
BODY_TYPE"PLUMBING"
HDL_TAP"TRUE";
"B \NAC \NWC"14;
"S \NAC"
BN"0"171;
%"TAP"
"1","(-1625,3575)","2","standard","I44";
;
CDS_LIB"standard"
BODY_TYPE"PLUMBING"
HDL_TAP"TRUE";
"B \NAC \NWC"14;
"S \NAC"
BN"4"163;
%"TAP"
"1","(-1625,3525)","2","standard","I45";
;
CDS_LIB"standard"
BODY_TYPE"PLUMBING"
HDL_TAP"TRUE";
"B \NAC \NWC"14;
"S \NAC"
BN"3"165;
%"TAP"
"1","(-1625,3675)","2","standard","I46";
;
CDS_LIB"standard"
BODY_TYPE"PLUMBING"
HDL_TAP"TRUE";
"B \NAC \NWC"14;
"S \NAC"
BN"6"81;
%"TAP"
"1","(-1625,3625)","2","standard","I47";
;
CDS_LIB"standard"
BODY_TYPE"PLUMBING"
HDL_TAP"TRUE";
"B \NAC \NWC"14;
"S \NAC"
BN"5"161;
%"TAP"
"1","(-1625,3825)","2","standard","I48";
;
CDS_LIB"standard"
BODY_TYPE"PLUMBING"
HDL_TAP"TRUE";
"B \NAC \NWC"13;
"S \NAC"
BN"1"170;
%"TAP"
"1","(-1625,3775)","2","standard","I49";
;
CDS_LIB"standard"
BODY_TYPE"PLUMBING"
HDL_TAP"TRUE";
"B \NAC \NWC"13;
"S \NAC"
BN"0"172;
%"TAP"
"1","(25,875)","0","standard","I50";
;
CDS_LIB"standard"
BODY_TYPE"PLUMBING"
HDL_TAP"TRUE";
"B \NAC \NWC"15;
"S \NAC"
BN"0"90;
%"TAP"
"1","(25,925)","0","standard","I51";
;
CDS_LIB"standard"
BODY_TYPE"PLUMBING"
HDL_TAP"TRUE";
"B \NAC \NWC"15;
"S \NAC"
BN"1"91;
%"TAP"
"1","(25,1025)","0","standard","I52";
;
CDS_LIB"standard"
BODY_TYPE"PLUMBING"
HDL_TAP"TRUE";
"B \NAC \NWC"15;
"S \NAC"
BN"3"93;
%"TAP"
"1","(25,975)","0","standard","I53";
;
CDS_LIB"standard"
BODY_TYPE"PLUMBING"
HDL_TAP"TRUE";
"B \NAC \NWC"15;
"S \NAC"
BN"2"92;
%"TAP"
"1","(25,1175)","0","standard","I54";
;
CDS_LIB"standard"
BODY_TYPE"PLUMBING"
HDL_TAP"TRUE";
"B \NAC \NWC"15;
"S \NAC"
BN"6"96;
%"TAP"
"1","(25,1125)","0","standard","I55";
;
CDS_LIB"standard"
BODY_TYPE"PLUMBING"
HDL_TAP"TRUE";
"B \NAC \NWC"15;
"S \NAC"
BN"5"95;
%"TAP"
"1","(25,1075)","0","standard","I56";
;
CDS_LIB"standard"
BODY_TYPE"PLUMBING"
HDL_TAP"TRUE";
"B \NAC \NWC"15;
"S \NAC"
BN"4"94;
%"TAP"
"1","(25,1225)","0","standard","I57";
;
CDS_LIB"standard"
BODY_TYPE"PLUMBING"
HDL_TAP"TRUE";
"B \NAC \NWC"15;
"S \NAC"
BN"7"97;
%"TAP"
"1","(25,1275)","0","standard","I58";
;
CDS_LIB"standard"
BODY_TYPE"PLUMBING"
HDL_TAP"TRUE";
"B \NAC \NWC"15;
"S \NAC"
BN"8"78;
%"TAP"
"1","(25,1325)","0","standard","I59";
;
CDS_LIB"standard"
BODY_TYPE"PLUMBING"
HDL_TAP"TRUE";
"B \NAC \NWC"15;
"S \NAC"
BN"9"77;
%"TAP"
"1","(25,1375)","0","standard","I60";
;
CDS_LIB"standard"
BODY_TYPE"PLUMBING"
HDL_TAP"TRUE";
"B \NAC \NWC"15;
"S \NAC"
BN"10"98;
%"TAP"
"1","(25,1425)","0","standard","I61";
;
CDS_LIB"standard"
BODY_TYPE"PLUMBING"
HDL_TAP"TRUE";
"B \NAC \NWC"15;
"S \NAC"
BN"11"99;
%"TAP"
"1","(25,1475)","0","standard","I62";
;
CDS_LIB"standard"
BODY_TYPE"PLUMBING"
HDL_TAP"TRUE";
"B \NAC \NWC"15;
"S \NAC"
BN"12"100;
%"TAP"
"1","(25,1525)","0","standard","I63";
;
CDS_LIB"standard"
BODY_TYPE"PLUMBING"
HDL_TAP"TRUE";
"B \NAC \NWC"15;
"S \NAC"
BN"13"101;
%"TAP"
"1","(25,1575)","0","standard","I64";
;
CDS_LIB"standard"
BODY_TYPE"PLUMBING"
HDL_TAP"TRUE";
"B \NAC \NWC"15;
"S \NAC"
BN"14"102;
%"TAP"
"1","(25,1625)","0","standard","I65";
;
CDS_LIB"standard"
BODY_TYPE"PLUMBING"
HDL_TAP"TRUE";
"B \NAC \NWC"15;
"S \NAC"
BN"15"103;
%"TAP"
"1","(25,1675)","0","standard","I66";
;
CDS_LIB"standard"
BODY_TYPE"PLUMBING"
HDL_TAP"TRUE";
"B \NAC \NWC"15;
"S \NAC"
BN"16"104;
%"TAP"
"1","(25,1725)","0","standard","I67";
;
CDS_LIB"standard"
BODY_TYPE"PLUMBING"
HDL_TAP"TRUE";
"B \NAC \NWC"15;
"S \NAC"
BN"17"105;
%"TAP"
"1","(25,1775)","0","standard","I68";
;
CDS_LIB"standard"
BODY_TYPE"PLUMBING"
HDL_TAP"TRUE";
"B \NAC \NWC"15;
"S \NAC"
BN"18"106;
%"TAP"
"1","(25,1825)","0","standard","I69";
;
CDS_LIB"standard"
BODY_TYPE"PLUMBING"
HDL_TAP"TRUE";
"B \NAC \NWC"15;
"S \NAC"
BN"19"107;
%"TAP"
"1","(25,1925)","0","standard","I70";
;
CDS_LIB"standard"
BODY_TYPE"PLUMBING"
HDL_TAP"TRUE";
"B \NAC \NWC"15;
"S \NAC"
BN"21"109;
%"TAP"
"1","(25,1875)","0","standard","I71";
;
CDS_LIB"standard"
BODY_TYPE"PLUMBING"
HDL_TAP"TRUE";
"B \NAC \NWC"15;
"S \NAC"
BN"20"108;
%"TAP"
"1","(25,2025)","0","standard","I72";
;
CDS_LIB"standard"
BODY_TYPE"PLUMBING"
HDL_TAP"TRUE";
"B \NAC \NWC"15;
"S \NAC"
BN"23"111;
%"TAP"
"1","(25,2075)","0","standard","I73";
;
CDS_LIB"standard"
BODY_TYPE"PLUMBING"
HDL_TAP"TRUE";
"B \NAC \NWC"15;
"S \NAC"
BN"24"112;
%"TAP"
"1","(25,1975)","0","standard","I74";
;
CDS_LIB"standard"
BODY_TYPE"PLUMBING"
HDL_TAP"TRUE";
"B \NAC \NWC"15;
"S \NAC"
BN"22"110;
%"TAP"
"1","(25,2125)","0","standard","I75";
;
CDS_LIB"standard"
BODY_TYPE"PLUMBING"
HDL_TAP"TRUE";
"B \NAC \NWC"15;
"S \NAC"
BN"25"113;
%"TAP"
"1","(25,2175)","0","standard","I76";
;
CDS_LIB"standard"
BODY_TYPE"PLUMBING"
HDL_TAP"TRUE";
"B \NAC \NWC"15;
"S \NAC"
BN"26"114;
%"TAP"
"1","(25,2225)","0","standard","I77";
;
CDS_LIB"standard"
BODY_TYPE"PLUMBING"
HDL_TAP"TRUE";
"B \NAC \NWC"15;
"S \NAC"
BN"27"115;
%"TAP"
"1","(25,2275)","0","standard","I78";
;
CDS_LIB"standard"
BODY_TYPE"PLUMBING"
HDL_TAP"TRUE";
"B \NAC \NWC"15;
"S \NAC"
BN"28"116;
%"TAP"
"1","(25,2325)","0","standard","I79";
;
CDS_LIB"standard"
BODY_TYPE"PLUMBING"
HDL_TAP"TRUE";
"B \NAC \NWC"15;
"S \NAC"
BN"29"117;
%"TAP"
"1","(25,2425)","0","standard","I80";
;
CDS_LIB"standard"
BODY_TYPE"PLUMBING"
HDL_TAP"TRUE";
"B \NAC \NWC"15;
"S \NAC"
BN"31"119;
%"TAP"
"1","(25,2375)","0","standard","I81";
;
CDS_LIB"standard"
BODY_TYPE"PLUMBING"
HDL_TAP"TRUE";
"B \NAC \NWC"15;
"S \NAC"
BN"30"118;
%"TAP"
"1","(25,2525)","0","standard","I82";
;
CDS_LIB"standard"
BODY_TYPE"PLUMBING"
HDL_TAP"TRUE";
"B \NAC \NWC"10;
"S \NAC"
BN"0"120;
%"TAP"
"1","(25,2575)","0","standard","I83";
;
CDS_LIB"standard"
BODY_TYPE"PLUMBING"
HDL_TAP"TRUE";
"B \NAC \NWC"10;
"S \NAC"
BN"1"121;
%"TAP"
"1","(25,2625)","0","standard","I84";
;
CDS_LIB"standard"
BODY_TYPE"PLUMBING"
HDL_TAP"TRUE";
"B \NAC \NWC"10;
"S \NAC"
BN"2"122;
%"TAP"
"1","(25,2675)","0","standard","I85";
;
CDS_LIB"standard"
BODY_TYPE"PLUMBING"
HDL_TAP"TRUE";
"B \NAC \NWC"10;
"S \NAC"
BN"3"123;
%"TAP"
"1","(25,2725)","0","standard","I86";
;
CDS_LIB"standard"
BODY_TYPE"PLUMBING"
HDL_TAP"TRUE";
"B \NAC \NWC"10;
"S \NAC"
BN"4"124;
%"TAP"
"1","(25,2775)","0","standard","I87";
;
CDS_LIB"standard"
BODY_TYPE"PLUMBING"
HDL_TAP"TRUE";
"B \NAC \NWC"10;
"S \NAC"
BN"5"125;
%"TAP"
"1","(25,2825)","0","standard","I88";
;
CDS_LIB"standard"
BODY_TYPE"PLUMBING"
HDL_TAP"TRUE";
"B \NAC \NWC"10;
"S \NAC"
BN"6"126;
%"TAP"
"1","(25,2925)","0","standard","I89";
;
CDS_LIB"standard"
BODY_TYPE"PLUMBING"
HDL_TAP"TRUE";
"B \NAC \NWC"10;
"S \NAC"
BN"8"128;
%"TAP"
"1","(25,2875)","0","standard","I90";
;
CDS_LIB"standard"
BODY_TYPE"PLUMBING"
HDL_TAP"TRUE";
"B \NAC \NWC"10;
"S \NAC"
BN"7"127;
%"TAP"
"1","(25,2975)","0","standard","I91";
;
CDS_LIB"standard"
BODY_TYPE"PLUMBING"
HDL_TAP"TRUE";
"B \NAC \NWC"10;
"S \NAC"
BN"9"129;
%"TAP"
"1","(25,3075)","0","standard","I92";
;
CDS_LIB"standard"
BODY_TYPE"PLUMBING"
HDL_TAP"TRUE";
"B \NAC \NWC"10;
"S \NAC"
BN"11"131;
%"TAP"
"1","(25,3025)","0","standard","I93";
;
CDS_LIB"standard"
BODY_TYPE"PLUMBING"
HDL_TAP"TRUE";
"B \NAC \NWC"10;
"S \NAC"
BN"10"130;
%"TAP"
"1","(25,3175)","0","standard","I94";
;
CDS_LIB"standard"
BODY_TYPE"PLUMBING"
HDL_TAP"TRUE";
"B \NAC \NWC"10;
"S \NAC"
BN"13"133;
%"TAP"
"1","(25,3225)","0","standard","I95";
;
CDS_LIB"standard"
BODY_TYPE"PLUMBING"
HDL_TAP"TRUE";
"B \NAC \NWC"10;
"S \NAC"
BN"14"134;
%"TAP"
"1","(25,3125)","0","standard","I96";
;
CDS_LIB"standard"
BODY_TYPE"PLUMBING"
HDL_TAP"TRUE";
"B \NAC \NWC"10;
"S \NAC"
BN"12"132;
%"TAP"
"1","(25,3325)","0","standard","I97";
;
CDS_LIB"standard"
BODY_TYPE"PLUMBING"
HDL_TAP"TRUE";
"B \NAC \NWC"10;
"S \NAC"
BN"16"136;
%"TAP"
"1","(25,3275)","0","standard","I98";
;
CDS_LIB"standard"
BODY_TYPE"PLUMBING"
HDL_TAP"TRUE";
"B \NAC \NWC"10;
"S \NAC"
BN"15"135;
%"TAP"
"1","(25,3475)","0","standard","I99";
;
CDS_LIB"standard"
BODY_TYPE"PLUMBING"
HDL_TAP"TRUE";
"B \NAC \NWC"10;
"S \NAC"
BN"19"139;
END.
